FILE_TYPE = CONNECTIVITY;
{Allegro Design Entry HDL 16.6-p007 (v16-6-112F) 10/10/2012}
"PAGE_NUMBER" = 260;
0"NC";
END.
